# T6G (Grand Teton) — schematic netlist excerpt (pin names and nets, part order shuffled) for the footprints in the layout excerpt that follows; sources: Cadence DE-HDL packaged netlist, KiCad conversion of 04192023_DAF0TMB3IC0_F0TG_MB_C_brd_V02_OCP.brd

PC314  Q_CAP  0.22UF 16V 10% X7R  pkg 0402  page 213 : A = SW_PVDDCR_CPU0_P1_BOOT5_RC ; B = SW_PVDDCR_CPU0_P1_PH5

(kicad_pcb
	(version 20260206)
	(generator "pcbnew")
	(generator_version "10.0")
	(general
		(thickness 1.6)
		(legacy_teardrops no)
	)
	(paper "A4")
	(title_block
		(title "04192023_DAF0TMB3IC0_F0TG_MB_C_brd_V02_OCP.brd")
		(comment 1 "Grand Teton / footprints 1179-1179 of 8354")
	)
	(layers
		(0 "F.Cu" signal "TOP")
		(4 "In1.Cu" signal "GND")
		(6 "In2.Cu" signal "IN1")
		(8 "In3.Cu" signal "GND1")
		(10 "In4.Cu" signal "IN2")
		(12 "In5.Cu" signal "GND2")
		(14 "In6.Cu" signal "IN3")
		(16 "In7.Cu" signal "GND3")
		(18 "In8.Cu" signal "VCC")
		(20 "In9.Cu" signal "VCC1")
		(22 "In10.Cu" signal "GND4")
		(24 "In11.Cu" signal "IN4")
		(26 "In12.Cu" signal "GND5")
		(28 "In13.Cu" signal "IN5")
		(30 "In14.Cu" signal "GND6")
		(32 "In15.Cu" signal "IN6")
		(34 "In16.Cu" signal "GND7")
		(2 "B.Cu" signal "BOTTOM")
		(9 "F.Adhes" user "F.Adhesive")
		(11 "B.Adhes" user "B.Adhesive")
		(13 "F.Paste" user "Package Geometry/Pastemask Top")
		(15 "B.Paste" user "Package Geometry/Pastemask Bottom")
		(5 "F.SilkS" user "Ref Des/Silkscreen Top")
		(7 "B.SilkS" user "Ref Des/Silkscreen Bottom")
		(1 "F.Mask" user "Board Geometry/Soldermask Top")
		(3 "B.Mask" user "Board Geometry/Soldermask Bottom")
		(17 "Dwgs.User" user "User.Drawings")
		(19 "Cmts.User" user "User.Comments")
		(21 "Eco1.User" user "User.Eco1")
		(23 "Eco2.User" user "User.Eco2")
		(25 "Edge.Cuts" user "Board Geometry/Outline")
		(27 "Margin" user)
		(31 "F.CrtYd" user "Package Geometry/Place Bound Top")
		(29 "B.CrtYd" user "Package Geometry/Place Bound Bottom")
		(35 "F.Fab" user "Ref Des/Assembly Top")
		(33 "B.Fab" user "Ref Des/Assembly Bottom")
	)
	(footprint ""
		(layer "F.Cu")
		(at 72.175116 -172.974 90)
		(property "Reference" "PC314"
			(at 0 0 90)
			(layer "F.SilkS")
			(hide yes)
			(effects
				(font
					(size 1.27 1.27)
				)
			)
		)
		(property "Value" ""
			(at 0 0 90)
			(layer "F.Fab")
			(effects
				(font
					(size 1.27 1.27)
				)
			)
		)
		(duplicate_pad_numbers_are_jumpers no)
		(fp_line
			(start 0.7874 -0.4064)
			(end 0.7874 0.4064)
			(stroke
				(width 0.1524)
				(type default)
			)
			(layer "F.SilkS")
		)
		(fp_line
			(start -0.7874 -0.4064)
			(end 0.7874 -0.4064)
			(stroke
				(width 0.1524)
				(type default)
			)
			(layer "F.SilkS")
		)
		(fp_line
			(start 0.7874 0.4064)
			(end -0.7874 0.4064)
			(stroke
				(width 0.1524)
				(type default)
			)
			(layer "F.SilkS")
		)
		(fp_line
			(start -0.7874 0.4064)
			(end -0.7874 -0.4064)
			(stroke
				(width 0.1524)
				(type default)
			)
			(layer "F.SilkS")
		)
		(fp_line
			(start -0.12065 -0.305054)
			(end -0.12065 -0.2794)
			(stroke
				(width 0.1)
				(type default)
			)
			(layer "F.Fab")
		)
		(fp_line
			(start -0.67945 -0.305054)
			(end -0.12065 -0.305054)
			(stroke
				(width 0.1)
				(type default)
			)
			(layer "F.Fab")
		)
		(fp_line
			(start 0.67945 -0.3048)
			(end 0.67945 0.3048)
			(stroke
				(width 0.1)
				(type default)
			)
			(layer "F.Fab")
		)
		(fp_line
			(start 0.12065 -0.3048)
			(end 0.67945 -0.3048)
			(stroke
				(width 0.1)
				(type default)
			)
			(layer "F.Fab")
		)
		(fp_line
			(start 0.12065 -0.2794)
			(end 0.12065 -0.3048)
			(stroke
				(width 0.1)
				(type default)
			)
			(layer "F.Fab")
		)
		(fp_line
			(start -0.12065 -0.2794)
			(end 0.12065 -0.2794)
			(stroke
				(width 0.1)
				(type default)
			)
			(layer "F.Fab")
		)
		(fp_line
			(start 0.120396 0.2794)
			(end -0.12065 0.2794)
			(stroke
				(width 0.1)
				(type default)
			)
			(layer "F.Fab")
		)
		(fp_line
			(start -0.12065 0.2794)
			(end -0.12065 0.3048)
			(stroke
				(width 0.1)
				(type default)
			)
			(layer "F.Fab")
		)
		(fp_line
			(start 0.67945 0.3048)
			(end 0.120396 0.3048)
			(stroke
				(width 0.1)
				(type default)
			)
			(layer "F.Fab")
		)
		(fp_line
			(start 0.120396 0.3048)
			(end 0.120396 0.2794)
			(stroke
				(width 0.1)
				(type default)
			)
			(layer "F.Fab")
		)
		(fp_line
			(start -0.12065 0.3048)
			(end -0.67945 0.3048)
			(stroke
				(width 0.1)
				(type default)
			)
			(layer "F.Fab")
		)
		(fp_line
			(start -0.67945 0.3048)
			(end -0.67945 -0.305054)
			(stroke
				(width 0.1)
				(type default)
			)
			(layer "F.Fab")
		)
		(pad "1" smd circle
			(at -0.40005 0 90)
			(size 0 0)
			(layers "F.Cu" "F.Mask" "F.Paste")
			(net "SW_PVDDCR_CPU0_P1_BOOT5_RC")
		)
		(pad "2" smd circle
			(at 0.40005 0 90)
			(size 0 0)
			(layers "F.Cu" "F.Mask" "F.Paste")
			(net "SW_PVDDCR_CPU0_P1_PH5")
		)
	)
)
